# S9S_MB_2U (Grand Teton) — schematic parts with pin connectivity, parts 1605–1605 of 6093; source: Cadence DE-HDL packaged netlist (pstxprt.dat, pstxnet.dat, pstchip.dat)

J12  SCONN288_ADR50017P087CC  SCONN288_ADR50017-P087CC IO  pkg DDR288S_1-1VXB  page 93
  1  VIN_BULK0  POWER  = P12V_S3_AUX_CPU0_NVDIMM
  2  RFU0  TRI  = TP_CHF_CPU0_DIMM2_FRU_0
  3  VIN_MGMT  POWER  = P3V3_AUX
  4  HSCL  IN  = I3C_SPD_DDREFGH_CPU0_LVC1_SCL_3
  5  HSDA  BI  = I3C_SPD_DDREFGH_CPU0_LVC1_SDA
  6  VSS0  POWER  = GND
  7  DQ0_A  BI  = M_F_CPU0_SA_DQ<0>
  8  VSS1  POWER  = GND
  9  DQ1_A  BI  = M_F_CPU0_SA_DQ<1>
  10  VSS2  POWER  = GND
  11  DQS0_A_T  BI  = M_F_CPU0_SA_DQS_DP<0>
  12  DQS0_A_C  BI  = M_F_CPU0_SA_DQS_DN<0>
  13  VSS3  POWER  = GND
  14  DQ4_A  BI  = M_F_CPU0_SA_DQ<4>
  15  VSS4  POWER  = GND
  16  DQ5_A  BI  = M_F_CPU0_SA_DQ<5>
  17  VSS5  POWER  = GND
  18  DQ8_A  BI  = M_F_CPU0_SA_DQ<8>
  19  VSS6  POWER  = GND
  20  DQ9_A  BI  = M_F_CPU0_SA_DQ<9>
  21  VSS7  POWER  = GND
  22  DQS1_A_T  BI  = M_F_CPU0_SA_DQS_DP<1>
  23  DQS1_A_C  BI  = M_F_CPU0_SA_DQS_DN<1>
  24  VSS8  POWER  = GND
  25  DQ12_A  BI  = M_F_CPU0_SA_DQ<12>
  26  VSS9  POWER  = GND
  27  DQ13_A  BI  = M_F_CPU0_SA_DQ<13>
  28  VSS10  POWER  = GND
  29  DQ16_A  BI  = M_F_CPU0_SA_DQ<16>
  30  VSS11  POWER  = GND
  31  DQ17_A  BI  = M_F_CPU0_SA_DQ<17>
  32  VSS12  POWER  = GND
  33  DQS2_A_T  BI  = M_F_CPU0_SA_DQS_DP<2>
  34  DQS2_A_C  BI  = M_F_CPU0_SA_DQS_DN<2>
  35  VSS13  POWER  = GND
  36  DQ20_A  BI  = M_F_CPU0_SA_DQ<20>
  37  VSS14  POWER  = GND
  38  DQ21_A  BI  = M_F_CPU0_SA_DQ<21>
  39  VSS15  POWER  = GND
  40  DQ24_A  BI  = M_F_CPU0_SA_DQ<24>
  41  VSS16  POWER  = GND
  42  DQ25_A  BI  = M_F_CPU0_SA_DQ<25>
  43  VSS17  POWER  = GND
  44  DQS3_A_T  BI  = M_F_CPU0_SA_DQS_DP<3>
  45  DQS3_A_C  BI  = M_F_CPU0_SA_DQS_DN<3>
  46  VSS18  POWER  = GND
  47  DQ28_A  BI  = M_F_CPU0_SA_DQ<28>
  48  VSS19  POWER  = GND
  49  DQ29_A  BI  = M_F_CPU0_SA_DQ<29>
  50  VSS20  POWER  = GND
  51  CB0_A  BI  = M_F_CPU0_SA_CB<0>
  52  VSS21  POWER  = GND
  53  CB1_A  BI  = M_F_CPU0_SA_CB<1>
  54  VSS22  POWER  = GND
  55  DQS4_A_T  BI  = M_F_CPU0_SA_DQS_DP<4>
  56  DQS4_A_C  BI  = M_F_CPU0_SA_DQS_DN<4>
  57  VSS23  POWER  = GND
  58  CB4_A  BI  = M_F_CPU0_SA_CB<4>
  59  VSS24  POWER  = GND
  60  CB5_A  BI  = M_F_CPU0_SA_CB<5>
  61  VSS25  POWER  = GND
  62  ALERT_N  OUT  = M_F_CPU0_ALERT_N
  63  VSS26  POWER  = GND
  64  CS0_A_N  IN  = M_F_CPU0_SA_CS_N<2>
  65  VSS27  POWER  = GND
  66  CA0_A  IN  = M_F_CPU0_SA_CA<0>
  67  VSS28  POWER  = GND
  68  CA2_A  IN  = M_F_CPU0_SA_CA<2>
  69  VSS29  POWER  = GND
  70  CA4_A  IN  = M_F_CPU0_SA_CA<4>
  71  VSS30  POWER  = GND
  72  CA6_A  IN  = M_F_CPU0_SA_CA<6>
  73  VSS31  POWER  = GND
  74  PAR_A  IN  = M_F_CPU0_SA_PAR
  75  VSS32  POWER  = GND
  76  CA0_B  IN  = M_F_CPU0_SB_CA<0>
  77  VSS33  POWER  = GND
  78  CA2_B  IN  = M_F_CPU0_SB_CA<2>
  79  VSS34  POWER  = GND
  80  CA4_B  IN  = M_F_CPU0_SB_CA<4>
  81  VSS35  POWER  = GND
  82  CA6_B  IN  = M_F_CPU0_SB_CA<6>
  83  VSS36  POWER  = GND
  84  CS0_B_N  IN  = M_F_CPU0_SB_CS_N<2>
  85  VSS37  POWER  = GND
  86  \lbd||rsp_a_n\  OUT  = M_F_CPU0_SA_RSP<1>
  87  \lbs||rsp_b_n\  OUT  = M_F_CPU0_SB_RSP<1>
  88  VSS38  POWER  = GND
  89  CB4_B  BI  = M_F_CPU0_SB_CB<4>
  90  VSS39  POWER  = GND
  91  CB5_B  BI  = M_F_CPU0_SB_CB<5>
  92  VSS40  POWER  = GND
  93  \dqs9_b_t||tdqs9_b_t||dbi4_b_n\  BI  = M_F_CPU0_SB_DQS_DP<9>
  94  \dqs9_b_c||tdqs9_b_c\  BI  = M_F_CPU0_SB_DQS_DN<9>
  95  VSS41  POWER  = GND
  96  CB0_B  BI  = M_F_CPU0_SB_CB<0>
  97  VSS42  POWER  = GND
  98  CB1_B  BI  = M_F_CPU0_SB_CB<1>
  99  VSS43  POWER  = GND
  100  DQ0_B  BI  = M_F_CPU0_SB_DQ<0>
  101  VSS44  POWER  = GND
  102  DQ1_B  BI  = M_F_CPU0_SB_DQ<1>
  103  VSS45  POWER  = GND
  104  DQS0_B_T  BI  = M_F_CPU0_SB_DQS_DP<0>
  105  DQS0_B_C  BI  = M_F_CPU0_SB_DQS_DN<0>
  106  VSS46  POWER  = GND
  107  DQ4_B  BI  = M_F_CPU0_SB_DQ<4>
  108  VSS47  POWER  = GND
  109  DQ5_B  BI  = M_F_CPU0_SB_DQ<5>
  110  VSS48  POWER  = GND
  111  DQ8_B  BI  = M_F_CPU0_SB_DQ<8>
  112  VSS49  POWER  = GND
  113  DQ9_B  BI  = M_F_CPU0_SB_DQ<9>
  114  VSS50  POWER  = GND
  115  DQS1_B_T  BI  = M_F_CPU0_SB_DQS_DP<1>
  116  DQS1_B_C  BI  = M_F_CPU0_SB_DQS_DN<1>
  117  VSS51  POWER  = GND
  118  DQ12_B  BI  = M_F_CPU0_SB_DQ<12>
  119  VSS52  POWER  = GND
  120  DQ13_B  BI  = M_F_CPU0_SB_DQ<13>
  121  VSS53  POWER  = GND
  122  DQ16_B  BI  = M_F_CPU0_SB_DQ<16>
  123  VSS54  POWER  = GND
  124  DQ17_B  BI  = M_F_CPU0_SB_DQ<17>
  125  VSS55  POWER  = GND
  126  DQS2_B_T  BI  = M_F_CPU0_SB_DQS_DP<2>
  127  DQS2_B_C  BI  = M_F_CPU0_SB_DQS_DN<2>
  128  VSS56  POWER  = GND
  129  DQ20_B  BI  = M_F_CPU0_SB_DQ<20>
  130  VSS57  POWER  = GND
  131  DQ21_B  BI  = M_F_CPU0_SB_DQ<21>
  132  VSS58  POWER  = GND
  133  DQ24_B  BI  = M_F_CPU0_SB_DQ<24>
  134  VSS59  POWER  = GND
  135  DQ25_B  BI  = M_F_CPU0_SB_DQ<25>
  136  VSS60  POWER  = GND
  137  DQS3_B_T  BI  = M_F_CPU0_SB_DQS_DP<3>
  138  DQS3_B_C  BI  = M_F_CPU0_SB_DQS_DN<3>
  139  VSS61  POWER  = GND
  140  DQ28_B  BI  = M_F_CPU0_SB_DQ<28>
  141  VSS62  POWER  = GND
  142  DQ29_B  BI  = M_F_CPU0_SB_DQ<29>
  143  VSS63  POWER  = GND
  144  RFU1  TRI  = TP_CHF_CPU0_DIMM2_FRU_1
  145  VIN_BULK1  POWER  = P12V_S3_AUX_CPU0_NVDIMM
  146  VIN_BULK2  POWER  = P12V_S3_AUX_CPU0_NVDIMM
  147  \pwr_good||fail_n\  BI  = PWRGD_CHF_CPU0_DIMM2
  148  HSA  IN  = PD_CHF_CPU0_DIMM2_SAA
  149  RFU2  TRI  = TP_CHF_CPU0_DIMM2_FRU_2
  150  RFU3  TRI  = TP_CHF_CPU0_DIMM2_FRU_3
  151  VSS64  POWER  = GND
  152  DQ2_A  BI  = M_F_CPU0_SA_DQ<2>
  153  VSS65  POWER  = GND
  154  DQ3_A  BI  = M_F_CPU0_SA_DQ<3>
  155  VSS66  POWER  = GND
  156  \dqs5_a_c||tdqs5_a_c||dqs5_a_t||tdqs5_a_t\  BI  = M_F_CPU0_SA_DQS_DN<5>
  157  \dqs5_a_t||tdqs5_a_t\  BI  = M_F_CPU0_SA_DQS_DP<5>
  158  VSS67  POWER  = GND
  159  DQ6_A  BI  = M_F_CPU0_SA_DQ<6>
  160  VSS68  POWER  = GND
  161  DQ7_A  BI  = M_F_CPU0_SA_DQ<7>
  162  VSS69  POWER  = GND
  163  DQ10_A  BI  = M_F_CPU0_SA_DQ<10>
  164  VSS70  POWER  = GND
  165  DQ11_A  BI  = M_F_CPU0_SA_DQ<11>
  166  VSS71  POWER  = GND
  167  \dqs6_a_c||tdqs6_a_c||dqs6_a_t||tdqs6_a_t\  BI  = M_F_CPU0_SA_DQS_DN<6>
  168  \dqs6_a_t||tdqs6_a_t\  BI  = M_F_CPU0_SA_DQS_DP<6>
  169  VSS72  POWER  = GND
  170  DQ14_A  BI  = M_F_CPU0_SA_DQ<14>
  171  VSS73  POWER  = GND
  172  DQ15_A  BI  = M_F_CPU0_SA_DQ<15>
  173  VSS74  POWER  = GND
  174  DQ18_A  BI  = M_F_CPU0_SA_DQ<18>
  175  VSS75  POWER  = GND
  176  DQ19_A  BI  = M_F_CPU0_SA_DQ<19>
  177  VSS76  POWER  = GND
  178  \dqs7_a_c||tdqs7_a_c\  BI  = M_F_CPU0_SA_DQS_DN<7>
  179  \dqs7_a_t||tdqs7_a_t\  BI  = M_F_CPU0_SA_DQS_DP<7>
  180  VSS77  POWER  = GND
  181  DQ22_A  BI  = M_F_CPU0_SA_DQ<22>
  182  VSS78  POWER  = GND
  183  DQ23_A  BI  = M_F_CPU0_SA_DQ<23>
  184  VSS79  POWER  = GND
  185  DQ26_A  BI  = M_F_CPU0_SA_DQ<26>
  186  VSS80  POWER  = GND
  187  DQ27_A  BI  = M_F_CPU0_SA_DQ<27>
  188  VSS81  POWER  = GND
  189  \dqs8_a_c||tdqs8_a_c\  BI  = M_F_CPU0_SA_DQS_DN<8>
  190  \dqs8_a_t||tdqs8_a_t\  BI  = M_F_CPU0_SA_DQS_DP<8>
  191  VSS82  POWER  = GND
  192  DQ30_A  BI  = M_F_CPU0_SA_DQ<30>
  193  VSS83  POWER  = GND
  194  DQ31_A  BI  = M_F_CPU0_SA_DQ<31>
  195  VSS84  POWER  = GND
  196  CB2_A  BI  = M_F_CPU0_SA_CB<2>
  197  VSS85  POWER  = GND
  198  CB3_A  BI  = M_F_CPU0_SA_CB<3>
  199  VSS86  POWER  = GND
  200  \dqs9_a_c||tdqs9_a_c\  BI  = M_F_CPU0_SA_DQS_DN<9>
  201  \dqs9_a_t||tdqs9_a_t\  BI  = M_F_CPU0_SA_DQS_DP<9>
  202  VSS87  POWER  = GND
  203  CB6_A  BI  = M_F_CPU0_SA_CB<6>
  204  VSS88  POWER  = GND
  205  CB7_A  BI  = M_F_CPU0_SA_CB<7>
  206  VSS89  POWER  = GND
  207  RESET_N  IN  = RST_M_EF_CPU0_FPGA_N
  208  VSS90  POWER  = GND
  209  CS1_A_N  IN  = M_F_CPU0_SA_CS_N<3>
  210  VSS91  POWER  = GND
  211  CA1_A  IN  = M_F_CPU0_SA_CA<1>
  212  VSS92  POWER  = GND
  213  CA3_A  IN  = M_F_CPU0_SA_CA<3>
  214  VSS93  POWER  = GND
  215  CA5_A  IN  = M_F_CPU0_SA_CA<5>
  216  VSS94  POWER  = GND
  217  CK_T  IN  = M_F_CPU0_CLK_DP<1>
  218  CK_C  IN  = M_F_CPU0_CLK_DN<1>
  219  VSS95  POWER  = GND
  220  RFU4  TRI  = TP_CHF_CPU0_DIMM2_FRU_4
  221  CA1_B  IN  = M_F_CPU0_SB_CA<1>
  222  VSS96  POWER  = GND
  223  CA3_B  IN  = M_F_CPU0_SB_CA<3>
  224  VSS97  POWER  = GND
  225  CA5_B  IN  = M_F_CPU0_SB_CA<5>
  226  VSS98  POWER  = GND
  227  PAR_B  IN  = M_F_CPU0_SB_PAR
  228  VSS99  POWER  = GND
  229  CS1_B_N  IN  = M_F_CPU0_SB_CS_N<3>
  230  VSS100  POWER  = GND
  231  RFU5  TRI  = TP_CHF_CPU0_DIMM2_FRU_5
  232  RFU6  TRI  = TP_CHF_CPU0_DIMM2_FRU_6
  233  VSS101  POWER  = GND
  234  CB6_B  BI  = M_F_CPU0_SB_CB<6>
  235  VSS102  POWER  = GND
  236  CB7_B  BI  = M_F_CPU0_SB_CB<7>
  237  VSS103  POWER  = GND
  238  DQS4_B_C  BI  = M_F_CPU0_SB_DQS_DN<4>
  239  DQS4_B_T  BI  = M_F_CPU0_SB_DQS_DP<4>
  240  VSS104  POWER  = GND
  241  CB2_B  BI  = M_F_CPU0_SB_CB<2>
  242  VSS105  POWER  = GND
  243  CB3_B  BI  = M_F_CPU0_SB_CB<3>
  244  VSS106  POWER  = GND
  245  DQ2_B  BI  = M_F_CPU0_SB_DQ<2>
  246  VSS107  POWER  = GND
  247  DQ3_B  BI  = M_F_CPU0_SB_DQ<3>
  248  VSS108  POWER  = GND
  249  \dqs5_b_c||tdqs5_b_c\  BI  = M_F_CPU0_SB_DQS_DN<5>
  250  \dqs5_b_t||tdqs5_b_t\  BI  = M_F_CPU0_SB_DQS_DP<5>
  251  VSS109  POWER  = GND
  252  DQ6_B  BI  = M_F_CPU0_SB_DQ<6>
  253  VSS110  POWER  = GND
  254  DQ7_B  BI  = M_F_CPU0_SB_DQ<7>
  255  VSS111  POWER  = GND
  256  DQ10_B  BI  = M_F_CPU0_SB_DQ<10>
  257  VSS112  POWER  = GND
  258  DQ11_B  BI  = M_F_CPU0_SB_DQ<11>
  259  VSS113  POWER  = GND
  260  \dqs6_b_c||tdqs6_b_c\  BI  = M_F_CPU0_SB_DQS_DN<6>
  261  \dqs6_b_t||tdqs6_b_t\  BI  = M_F_CPU0_SB_DQS_DP<6>
  262  VSS114  POWER  = GND
  263  DQ14_B  BI  = M_F_CPU0_SB_DQ<14>
  264  VSS115  POWER  = GND
  265  DQ15_B  BI  = M_F_CPU0_SB_DQ<15>
  266  VSS116  POWER  = GND
  267  DQ18_B  BI  = M_F_CPU0_SB_DQ<18>
  268  VSS117  POWER  = GND
  269  DQ19_B  BI  = M_F_CPU0_SB_DQ<19>
  270  VSS118  POWER  = GND
  271  \dqs7_b_c||tdqs7_b_c\  BI  = M_F_CPU0_SB_DQS_DN<7>
  272  \dqs7_b_t||tdqs7_b_t\  BI  = M_F_CPU0_SB_DQS_DP<7>
  273  VSS119  POWER  = GND
  274  DQ22_B  BI  = M_F_CPU0_SB_DQ<22>
  275  VSS120  POWER  = GND
  276  DQ23_B  BI  = M_F_CPU0_SB_DQ<23>
  277  VSS121  POWER  = GND
  278  DQ26_B  BI  = M_F_CPU0_SB_DQ<26>
  279  VSS122  POWER  = GND
  280  DQ27_B  BI  = M_F_CPU0_SB_DQ<27>
  281  VSS123  POWER  = GND
  282  \dqs8_b_c||tdqs8_b_c\  BI  = M_F_CPU0_SB_DQS_DN<8>
  283  \dqs8_b_t||tdqs8_b_t\  BI  = M_F_CPU0_SB_DQS_DP<8>
  284  VSS124  POWER  = GND
  285  DQ30_B  BI  = M_F_CPU0_SB_DQ<30>
  286  VSS125  POWER  = GND
  287  DQ31_B  BI  = M_F_CPU0_SB_DQ<31>
  288  VSS126  POWER  = GND
  G1  G1  POWER  = GND
  G2  G2  POWER  = GND
  G3  G3  POWER  = GND
